FILE_TYPE = MULTI_PHYS_TABLE;

PART 'PI6CV304LE'

{========================================================================================}
:VALUE        | PART_TYPE | MATERIAL | PART_NUMBER      = PART_NUMBER   | JEDEC_TYPE | DESCRIPTION                      | MANUFTR | MANUF_PN     | RD_CMPLS_LVL | CMPLS_LVL | FROM_PJ     | CLASS | DIP_SMD | DATA                     | EE_CHECK_LIST | FP_ECN | PSL | LIFECYCLE      | CREATOR | STANDARD | CREATEDAY  | STATUS ;
{========================================================================================}
 'PI6CV304LE' | 'SMLF'    | 'IC'     | 'AL000304K01'(!) = 'AL000304K01' |'TSSOP8'| 'IC OTHER(8P) PI6CV304LE(TSSOP)' | 'PIM'   | 'PI6CV304LE' | 'EP'         | 'EP'      | 'S4E-JAMES' | 'IC'  | ''      | 'PI6CV304_PI6CV2304.pdf' | ''            | ''     | ''  | ''               | ''      | ''       | '20111206' | ''    
 'PI6CV304LE' | 'SMLF'    | 'EMPTY'  | 'AL000304K01'(!) = 'AL000304K01' |'TSSOP8'| 'IC OTHER(8P) PI6CV304LE(TSSOP)' | 'PIM'   | 'PI6CV304LE' | 'EP'         | 'EP'      | 'S4E-JAMES' | 'IC'  | ''      | 'PI6CV304_PI6CV2304.pdf' | ''            | ''     | ''  | ''               | ''      | ''       | '20111206' | ''    

END_PART

END.

